# S9S_MB_2U (Grand Teton) — schematic parts with pin connectivity, parts 1665–1667 of 6093; source: Cadence DE-HDL packaged netlist (pstxprt.dat, pstxnet.dat, pstchip.dat)

J109  CONN112_10137002101LF  CONN112_10137002-101LF IO  pkg HSD_F112D8_P2W1-2_RDH  page 140
  A1  A1  BI  = BMC_MONITER_BUF
  A2  A2  BI  = GND
  A3  A3  BI  = BIC_MONITER
  A4  A4  BI  = GND
  A5  A5  BI  = SMB_BMC_SWB_BUF_SCL
  A6  A6  BI  = GND
  A7  A7  BI  = SMB_BMC_SWB_BUF_SDA
  A8  A8  BI  = GND
  B1  B1  BI  = GND
  B2  B2  BI  = P5E_CPU1_PE3_RX_DP<6>
  B3  B3  BI  = GND
  B4  B4  BI  = P5E_CPU1_PE3_RX_DP<4>
  B5  B5  BI  = GND
  B6  B6  BI  = P5E_CPU1_PE3_RX_DN<2>
  B7  B7  BI  = GND
  B8  B8  BI  = P5E_CPU1_PE3_RX_DP<0>
  C1  C1  BI  = P5E_CPU1_PE3_RX_DP<7>
  C2  C2  BI  = P5E_CPU1_PE3_RX_DN<6>
  C3  C3  BI  = P5E_CPU1_PE3_RX_DP<5>
  C4  C4  BI  = P5E_CPU1_PE3_RX_DN<4>
  C5  C5  BI  = P5E_CPU1_PE3_RX_DN<3>
  C6  C6  BI  = P5E_CPU1_PE3_RX_DP<2>
  C7  C7  BI  = P5E_CPU1_PE3_RX_DN<1>
  C8  C8  BI  = P5E_CPU1_PE3_RX_DN<0>
  D1  D1  BI  = P5E_CPU1_PE3_RX_DN<7>
  D2  D2  BI  = GND
  D3  D3  BI  = P5E_CPU1_PE3_RX_DN<5>
  D4  D4  BI  = GND
  D5  D5  BI  = P5E_CPU1_PE3_RX_DP<3>
  D6  D6  BI  = GND
  D7  D7  BI  = P5E_CPU1_PE3_RX_DP<1>
  D8  D8  BI  = GND
  E1  E1  BI  = GND
  E2  E2  BI  = P5E_CPU1_PE2_RX_DP<6>
  E3  E3  BI  = GND
  E4  E4  BI  = P5E_CPU1_PE2_RX_DP<4>
  E5  E5  BI  = GND
  E6  E6  BI  = P5E_CPU1_PE2_RX_DP<2>
  E7  E7  BI  = GND
  E8  E8  BI  = P5E_CPU1_PE2_RX_DP<0>
  F1  F1  BI  = P5E_CPU1_PE2_RX_DP<7>
  F2  F2  BI  = P5E_CPU1_PE2_RX_DN<6>
  F3  F3  BI  = P5E_CPU1_PE2_RX_DP<5>
  F4  F4  BI  = P5E_CPU1_PE2_RX_DN<4>
  F5  F5  BI  = P5E_CPU1_PE2_RX_DP<3>
  F6  F6  BI  = P5E_CPU1_PE2_RX_DN<2>
  F7  F7  BI  = P5E_CPU1_PE2_RX_DP<1>
  F8  F8  BI  = P5E_CPU1_PE2_RX_DN<0>
  G1  G1  BI  = P5E_CPU1_PE2_RX_DN<7>
  G2  G2  BI  = GND
  G3  G3  BI  = P5E_CPU1_PE2_RX_DN<5>
  G4  G4  BI  = GND
  G5  G5  BI  = P5E_CPU1_PE2_RX_DN<3>
  G6  G6  BI  = GND
  G7  G7  BI  = P5E_CPU1_PE2_RX_DN<1>
  G8  G8  BI  = GND
  H1  H1  BI  = GND
  H2  H2  BI  = P5E_CPU1_PE3_TX_C_DN<6>
  H3  H3  BI  = GND
  H4  H4  BI  = P5E_CPU1_PE3_TX_C_DN<4>
  H5  H5  BI  = GND
  H6  H6  BI  = P5E_CPU1_PE3_TX_C_DN<2>
  H7  H7  BI  = GND
  H8  H8  BI  = P5E_CPU1_PE3_TX_C_DP<0>
  I1  I1  BI  = P5E_CPU1_PE3_TX_C_DN<7>
  I2  I2  BI  = P5E_CPU1_PE3_TX_C_DP<6>
  I3  I3  BI  = P5E_CPU1_PE3_TX_C_DN<5>
  I4  I4  BI  = P5E_CPU1_PE3_TX_C_DP<4>
  I5  I5  BI  = P5E_CPU1_PE3_TX_C_DN<3>
  I6  I6  BI  = P5E_CPU1_PE3_TX_C_DP<2>
  I7  I7  BI  = P5E_CPU1_PE3_TX_C_DN<1>
  I8  I8  BI  = P5E_CPU1_PE3_TX_C_DN<0>
  J1  J1  BI  = P5E_CPU1_PE3_TX_C_DP<7>
  J2  J2  BI  = GND
  J3  J3  BI  = P5E_CPU1_PE3_TX_C_DP<5>
  J4  J4  BI  = GND
  J5  J5  BI  = P5E_CPU1_PE3_TX_C_DP<3>
  J6  J6  BI  = GND
  J7  J7  BI  = P5E_CPU1_PE3_TX_C_DP<1>
  J8  J8  BI  = GND
  K1  K1  BI  = GND
  K2  K2  BI  = P5E_CPU1_PE2_TX_C_DP<6>
  K3  K3  BI  = GND
  K4  K4  BI  = P5E_CPU1_PE2_TX_C_DP<4>
  K5  K5  BI  = GND
  K6  K6  BI  = P5E_CPU1_PE2_TX_C_DP<2>
  K7  K7  BI  = GND
  K8  K8  BI  = P5E_CPU1_PE2_TX_C_DP<0>
  L1  L1  BI  = P5E_CPU1_PE2_TX_C_DP<7>
  L2  L2  BI  = P5E_CPU1_PE2_TX_C_DN<6>
  L3  L3  BI  = P5E_CPU1_PE2_TX_C_DP<5>
  L4  L4  BI  = P5E_CPU1_PE2_TX_C_DN<4>
  L5  L5  BI  = P5E_CPU1_PE2_TX_C_DP<3>
  L6  L6  BI  = P5E_CPU1_PE2_TX_C_DN<2>
  L7  L7  BI  = P5E_CPU1_PE2_TX_C_DP<1>
  L8  L8  BI  = P5E_CPU1_PE2_TX_C_DN<0>
  M1  M1  BI  = P5E_CPU1_PE2_TX_C_DN<7>
  M2  M2  BI  = GND
  M3  M3  BI  = P5E_CPU1_PE2_TX_C_DN<5>
  M4  M4  BI  = GND
  M5  M5  BI  = P5E_CPU1_PE2_TX_C_DN<3>
  M6  M6  BI  = GND
  M7  M7  BI  = P5E_CPU1_PE2_TX_C_DN<1>
  M8  M8  BI  = GND
  N1  N1  BI  = GND
  N2  N2  BI  = GPU_FPGA_EROT_FATALERR_N
  N3  N3  BI  = GND
  N4  N4  BI  = GPU_3V3IO_RSVD0_FFU
  N5  N5  BI  = GND
  N6  N6  BI  = GPU_3V3IO_RSVD1_FFU
  N7  N7  BI  = GND
  N8  N8  BI  = PRSNT_CABLE_GPU_B3_N

J110  CONN112_10137002101LF  CONN112_10137002-101LF IO  pkg HSD_F112D8_P2W1-2_RDH  page 141
  A1  A1  BI  = GPU_FPGA_EROT_RECOV_BUF_N
  A2  A2  BI  = GND
  A3  A3  BI  = GPU_HMC_PRSNT_N
  A4  A4  BI  = GND
  A5  A5  BI  = GPU_BASE_HMC_READY
  A6  A6  BI  = GND
  A7  A7  BI  = GPU_BASE_STBY_EN_BUF
  A8  A8  BI  = GND
  B1  B1  BI  = GND
  B2  B2  BI  = P5E_CPU1_PE3_RX_DP<14>
  B3  B3  BI  = GND
  B4  B4  BI  = P5E_CPU1_PE3_RX_DP<12>
  B5  B5  BI  = GND
  B6  B6  BI  = P5E_CPU1_PE3_RX_DN<10>
  B7  B7  BI  = GND
  B8  B8  BI  = P5E_CPU1_PE3_RX_DN<8>
  C1  C1  BI  = P5E_CPU1_PE3_RX_DP<15>
  C2  C2  BI  = P5E_CPU1_PE3_RX_DN<14>
  C3  C3  BI  = P5E_CPU1_PE3_RX_DP<13>
  C4  C4  BI  = P5E_CPU1_PE3_RX_DN<12>
  C5  C5  BI  = P5E_CPU1_PE3_RX_DN<11>
  C6  C6  BI  = P5E_CPU1_PE3_RX_DP<10>
  C7  C7  BI  = P5E_CPU1_PE3_RX_DN<9>
  C8  C8  BI  = P5E_CPU1_PE3_RX_DP<8>
  D1  D1  BI  = P5E_CPU1_PE3_RX_DN<15>
  D2  D2  BI  = GND
  D3  D3  BI  = P5E_CPU1_PE3_RX_DN<13>
  D4  D4  BI  = GND
  D5  D5  BI  = P5E_CPU1_PE3_RX_DP<11>
  D6  D6  BI  = GND
  D7  D7  BI  = P5E_CPU1_PE3_RX_DP<9>
  D8  D8  BI  = GND
  E1  E1  BI  = GND
  E2  E2  BI  = P5E_CPU1_PE2_RX_DP<14>
  E3  E3  BI  = GND
  E4  E4  BI  = P5E_CPU1_PE2_RX_DP<12>
  E5  E5  BI  = GND
  E6  E6  BI  = P5E_CPU1_PE2_RX_DP<10>
  E7  E7  BI  = GND
  E8  E8  BI  = P5E_CPU1_PE2_RX_DP<8>
  F1  F1  BI  = P5E_CPU1_PE2_RX_DP<15>
  F2  F2  BI  = P5E_CPU1_PE2_RX_DN<14>
  F3  F3  BI  = P5E_CPU1_PE2_RX_DP<13>
  F4  F4  BI  = P5E_CPU1_PE2_RX_DN<12>
  F5  F5  BI  = P5E_CPU1_PE2_RX_DP<11>
  F6  F6  BI  = P5E_CPU1_PE2_RX_DN<10>
  F7  F7  BI  = P5E_CPU1_PE2_RX_DP<9>
  F8  F8  BI  = P5E_CPU1_PE2_RX_DN<8>
  G1  G1  BI  = P5E_CPU1_PE2_RX_DN<15>
  G2  G2  BI  = GND
  G3  G3  BI  = P5E_CPU1_PE2_RX_DN<13>
  G4  G4  BI  = GND
  G5  G5  BI  = P5E_CPU1_PE2_RX_DN<11>
  G6  G6  BI  = GND
  G7  G7  BI  = P5E_CPU1_PE2_RX_DN<9>
  G8  G8  BI  = GND
  H1  H1  BI  = GND
  H2  H2  BI  = P5E_CPU1_PE3_TX_C_DN<14>
  H3  H3  BI  = GND
  H4  H4  BI  = P5E_CPU1_PE3_TX_C_DN<12>
  H5  H5  BI  = GND
  H6  H6  BI  = P5E_CPU1_PE3_TX_C_DN<10>
  H7  H7  BI  = GND
  H8  H8  BI  = P5E_CPU1_PE3_TX_C_DN<8>
  I1  I1  BI  = P5E_CPU1_PE3_TX_C_DN<15>
  I2  I2  BI  = P5E_CPU1_PE3_TX_C_DP<14>
  I3  I3  BI  = P5E_CPU1_PE3_TX_C_DN<13>
  I4  I4  BI  = P5E_CPU1_PE3_TX_C_DP<12>
  I5  I5  BI  = P5E_CPU1_PE3_TX_C_DN<11>
  I6  I6  BI  = P5E_CPU1_PE3_TX_C_DP<10>
  I7  I7  BI  = P5E_CPU1_PE3_TX_C_DN<9>
  I8  I8  BI  = P5E_CPU1_PE3_TX_C_DP<8>
  J1  J1  BI  = P5E_CPU1_PE3_TX_C_DP<15>
  J2  J2  BI  = GND
  J3  J3  BI  = P5E_CPU1_PE3_TX_C_DP<13>
  J4  J4  BI  = GND
  J5  J5  BI  = P5E_CPU1_PE3_TX_C_DP<11>
  J6  J6  BI  = GND
  J7  J7  BI  = P5E_CPU1_PE3_TX_C_DP<9>
  J8  J8  BI  = GND
  K1  K1  BI  = GND
  K2  K2  BI  = P5E_CPU1_PE2_TX_C_DP<14>
  K3  K3  BI  = GND
  K4  K4  BI  = P5E_CPU1_PE2_TX_C_DP<12>
  K5  K5  BI  = GND
  K6  K6  BI  = P5E_CPU1_PE2_TX_C_DP<10>
  K7  K7  BI  = GND
  K8  K8  BI  = P5E_CPU1_PE2_TX_C_DP<8>
  L1  L1  BI  = P5E_CPU1_PE2_TX_C_DP<15>
  L2  L2  BI  = P5E_CPU1_PE2_TX_C_DN<14>
  L3  L3  BI  = P5E_CPU1_PE2_TX_C_DP<13>
  L4  L4  BI  = P5E_CPU1_PE2_TX_C_DN<12>
  L5  L5  BI  = P5E_CPU1_PE2_TX_C_DP<11>
  L6  L6  BI  = P5E_CPU1_PE2_TX_C_DN<10>
  L7  L7  BI  = P5E_CPU1_PE2_TX_C_DP<9>
  L8  L8  BI  = P5E_CPU1_PE2_TX_C_DN<8>
  M1  M1  BI  = P5E_CPU1_PE2_TX_C_DN<15>
  M2  M2  BI  = GND
  M3  M3  BI  = P5E_CPU1_PE2_TX_C_DN<13>
  M4  M4  BI  = GND
  M5  M5  BI  = P5E_CPU1_PE2_TX_C_DN<11>
  M6  M6  BI  = GND
  M7  M7  BI  = P5E_CPU1_PE2_TX_C_DN<9>
  M8  M8  BI  = GND
  N1  N1  BI  = GND
  N2  N2  BI  = GPU_FPGA_BOOT_EN_BUF
  N3  N3  BI  = GND
  N4  N4  BI  = FM_SMB_1_ALERT_GPU_N
  N5  N5  BI  = GND
  N6  N6  BI  = FM_SMB_2_ALERT_GPU_N
  N7  N7  BI  = GND
  N8  N8  BI  = GPU_FPGA_EROT_RST_BUF_N

J111  CONN112_10137002101LF  CONN112_10137002-101LF IO  pkg HSD_F112D8_P2W1-2_RDH  page 142
  A1  A1  BI  = GPU_PEX_STRAP1
  A2  A2  BI  = GND
  A3  A3  BI  = GPU_BASE_ID0
  A4  A4  BI  = GND
  A5  A5  BI  = GPU_PEX_STRAP0
  A6  A6  BI  = GND
  A7  A7  BI  = GPU_FPGA_RST_R_BUF_N
  A8  A8  BI  = GND
  B1  B1  BI  = GND
  B2  B2  BI  = P5E_CPU1_PE0_RX_DN<6>
  B3  B3  BI  = GND
  B4  B4  BI  = P5E_CPU1_PE0_RX_DN<4>
  B5  B5  BI  = GND
  B6  B6  BI  = P5E_CPU1_PE0_RX_DN<2>
  B7  B7  BI  = GND
  B8  B8  BI  = P5E_CPU1_PE0_RX_DN<0>
  C1  C1  BI  = P5E_CPU1_PE0_RX_DN<7>
  C2  C2  BI  = P5E_CPU1_PE0_RX_DP<6>
  C3  C3  BI  = P5E_CPU1_PE0_RX_DN<5>
  C4  C4  BI  = P5E_CPU1_PE0_RX_DP<4>
  C5  C5  BI  = P5E_CPU1_PE0_RX_DP<3>
  C6  C6  BI  = P5E_CPU1_PE0_RX_DP<2>
  C7  C7  BI  = P5E_CPU1_PE0_RX_DP<1>
  C8  C8  BI  = P5E_CPU1_PE0_RX_DP<0>
  D1  D1  BI  = P5E_CPU1_PE0_RX_DP<7>
  D2  D2  BI  = GND
  D3  D3  BI  = P5E_CPU1_PE0_RX_DP<5>
  D4  D4  BI  = GND
  D5  D5  BI  = P5E_CPU1_PE0_RX_DN<3>
  D6  D6  BI  = GND
  D7  D7  BI  = P5E_CPU1_PE0_RX_DN<1>
  D8  D8  BI  = GND
  E1  E1  BI  = GND
  E2  E2  BI  = P5E_CPU1_PE4_RX_DP<9>
  E3  E3  BI  = GND
  E4  E4  BI  = P5E_CPU1_PE4_RX_DP<11>
  E5  E5  BI  = GND
  E6  E6  BI  = P5E_CPU1_PE4_RX_DP<13>
  E7  E7  BI  = GND
  E8  E8  BI  = P5E_CPU1_PE4_RX_DP<15>
  F1  F1  BI  = P5E_CPU1_PE4_RX_DN<8>
  F2  F2  BI  = P5E_CPU1_PE4_RX_DN<9>
  F3  F3  BI  = P5E_CPU1_PE4_RX_DN<10>
  F4  F4  BI  = P5E_CPU1_PE4_RX_DN<11>
  F5  F5  BI  = P5E_CPU1_PE4_RX_DN<12>
  F6  F6  BI  = P5E_CPU1_PE4_RX_DN<13>
  F7  F7  BI  = P5E_CPU1_PE4_RX_DN<14>
  F8  F8  BI  = P5E_CPU1_PE4_RX_DN<15>
  G1  G1  BI  = P5E_CPU1_PE4_RX_DP<8>
  G2  G2  BI  = GND
  G3  G3  BI  = P5E_CPU1_PE4_RX_DP<10>
  G4  G4  BI  = GND
  G5  G5  BI  = P5E_CPU1_PE4_RX_DP<12>
  G6  G6  BI  = GND
  G7  G7  BI  = P5E_CPU1_PE4_RX_DP<14>
  G8  G8  BI  = GND
  H1  H1  BI  = GND
  H2  H2  BI  = P5E_CPU1_PE0_TX_C_DN<6>
  H3  H3  BI  = GND
  H4  H4  BI  = P5E_CPU1_PE0_TX_C_DN<4>
  H5  H5  BI  = GND
  H6  H6  BI  = P5E_CPU1_PE0_TX_C_DN<2>
  H7  H7  BI  = GND
  H8  H8  BI  = P5E_CPU1_PE0_TX_C_DN<0>
  I1  I1  BI  = P5E_CPU1_PE0_TX_C_DN<7>
  I2  I2  BI  = P5E_CPU1_PE0_TX_C_DP<6>
  I3  I3  BI  = P5E_CPU1_PE0_TX_C_DN<5>
  I4  I4  BI  = P5E_CPU1_PE0_TX_C_DP<4>
  I5  I5  BI  = P5E_CPU1_PE0_TX_C_DN<3>
  I6  I6  BI  = P5E_CPU1_PE0_TX_C_DP<2>
  I7  I7  BI  = P5E_CPU1_PE0_TX_C_DN<1>
  I8  I8  BI  = P5E_CPU1_PE0_TX_C_DP<0>
  J1  J1  BI  = P5E_CPU1_PE0_TX_C_DP<7>
  J2  J2  BI  = GND
  J3  J3  BI  = P5E_CPU1_PE0_TX_C_DP<5>
  J4  J4  BI  = GND
  J5  J5  BI  = P5E_CPU1_PE0_TX_C_DP<3>
  J6  J6  BI  = GND
  J7  J7  BI  = P5E_CPU1_PE0_TX_C_DP<1>
  J8  J8  BI  = GND
  K1  K1  BI  = GND
  K2  K2  BI  = P5E_CPU1_PE4_TX_C_DN<9>
  K3  K3  BI  = GND
  K4  K4  BI  = P5E_CPU1_PE4_TX_C_DP<11>
  K5  K5  BI  = GND
  K6  K6  BI  = P5E_CPU1_PE4_TX_C_DN<13>
  K7  K7  BI  = GND
  K8  K8  BI  = P5E_CPU1_PE4_TX_C_DN<15>
  L1  L1  BI  = P5E_CPU1_PE4_TX_C_DN<8>
  L2  L2  BI  = P5E_CPU1_PE4_TX_C_DP<9>
  L3  L3  BI  = P5E_CPU1_PE4_TX_C_DN<10>
  L4  L4  BI  = P5E_CPU1_PE4_TX_C_DN<11>
  L5  L5  BI  = P5E_CPU1_PE4_TX_C_DN<12>
  L6  L6  BI  = P5E_CPU1_PE4_TX_C_DP<13>
  L7  L7  BI  = P5E_CPU1_PE4_TX_C_DN<14>
  L8  L8  BI  = P5E_CPU1_PE4_TX_C_DP<15>
  M1  M1  BI  = P5E_CPU1_PE4_TX_C_DP<8>
  M2  M2  BI  = GND
  M3  M3  BI  = P5E_CPU1_PE4_TX_C_DP<10>
  M4  M4  BI  = GND
  M5  M5  BI  = P5E_CPU1_PE4_TX_C_DP<12>
  M6  M6  BI  = GND
  M7  M7  BI  = P5E_CPU1_PE4_TX_C_DP<14>
  M8  M8  BI  = GND
  N1  N1  BI  = GND
  N2  N2  BI  = GPU_PRSNT_N
  N3  N3  BI  = GND
  N4  N4  BI  = FM_GPU_PWR_EN_R_BUF
  N5  N5  BI  = GND
  N6  N6  BI  = FM_GPU_PWRGD
  N7  N7  BI  = GND
  N8  N8  BI  = GPU_BASE_ID1
